(kicad_pcb
	(version 20241229)
	(generator "pcbnew")
	(generator_version "9.0")
	(general
		(thickness 1.711)
		(legacy_teardrops no)
	)
	(paper "A4")
	(title_block
		(title "Antmicro Baseboard for Jetson AGX Thor")
		(date "2026-02-18")
		(rev "1.1.0")
		(company "Antmicro Ltd")
		(comment 1 "www.antmicro.com")
		(comment 9 "footprints 638-641 of 1170")
	)
	(layers
		(0 "F.Cu" signal)
		(4 "In1.Cu" signal)
		(6 "In2.Cu" signal)
		(8 "In3.Cu" signal)
		(10 "In4.Cu" jumper)
		(12 "In5.Cu" signal)
		(14 "In6.Cu" signal)
		(16 "In7.Cu" signal)
		(18 "In8.Cu" signal)
		(2 "B.Cu" signal)
		(9 "F.Adhes" user "F.Adhesive")
		(11 "B.Adhes" user "B.Adhesive")
		(13 "F.Paste" user)
		(15 "B.Paste" user)
		(5 "F.SilkS" user "F.Silkscreen")
		(7 "B.SilkS" user "B.Silkscreen")
		(1 "F.Mask" user)
		(3 "B.Mask" user)
		(17 "Dwgs.User" user "User.Drawings")
		(19 "Cmts.User" user "User.Comments")
		(21 "Eco1.User" user "User.Eco1")
		(23 "Eco2.User" user "User.Eco2")
		(25 "Edge.Cuts" user)
		(27 "Margin" user)
		(31 "F.CrtYd" user "F.Courtyard")
		(29 "B.CrtYd" user "B.Courtyard")
		(35 "F.Fab" user)
		(33 "B.Fab" user)
	)
	(footprint "antmicro-footprints:SOT-523"
		(layer "B.Cu")
		(at 97.75 62.92 -90)
		(property "Reference" "Q7"
			(at -0.92 2.5 270)
			(layer "B.SilkS")
			(effects
				(font
					(size 0.7 0.7)
					(thickness 0.15)
				)
				(justify left bottom mirror)
			)
		)
		(property "Value" "DMG1012T-7"
			(at 0.1 -1.824 90)
			(layer "B.Fab")
			(effects
				(font
					(size 0.7 0.7)
					(thickness 0.15)
				)
				(justify left bottom mirror)
			)
		)
		(property "Datasheet" "https://www.diodes.com/assets/Datasheets/ds31783.pdf"
			(at 0 0 90)
			(layer "B.Fab")
			(hide yes)
			(effects
				(font
					(size 1.27 1.27)
					(thickness 0.15)
				)
				(justify mirror)
			)
		)
		(property "Description" "Power MOSFET, N Channel, 20 V, 630 mA, 0.3 ohm, SOT-523, Surface Mount"
			(at 0 0 90)
			(layer "B.Fab")
			(hide yes)
			(effects
				(font
					(size 1.27 1.27)
					(thickness 0.15)
				)
				(justify mirror)
			)
		)
		(property "MPN" "DMG1012T-7"
			(at 0 0 90)
			(unlocked yes)
			(layer "B.Fab")
			(hide yes)
			(effects
				(font
					(size 1 1)
					(thickness 0.15)
				)
				(justify mirror)
			)
		)
		(property "Manufacturer" "Diodes Incorporated"
			(at 0 0 90)
			(unlocked yes)
			(layer "B.Fab")
			(hide yes)
			(effects
				(font
					(size 1 1)
					(thickness 0.15)
				)
				(justify mirror)
			)
		)
		(property "Author" "Antmicro"
			(at 0 0 90)
			(unlocked yes)
			(layer "B.Fab")
			(hide yes)
			(effects
				(font
					(size 1 1)
					(thickness 0.15)
				)
				(justify mirror)
			)
		)
		(property "License" "Apache-2.0"
			(at 0 0 90)
			(unlocked yes)
			(layer "B.Fab")
			(hide yes)
			(effects
				(font
					(size 1 1)
					(thickness 0.15)
				)
				(justify mirror)
			)
		)
		(sheetname "/SoM_Power/")
		(sheetfile "som_power.kicad_sch")
		(attr smd)
		(fp_line
			(start -0.725 0.551)
			(end -0.277 0.551)
			(stroke
				(width 0.15)
				(type solid)
			)
			(layer "B.SilkS")
		)
		(fp_line
			(start -0.277 0.551)
			(end -0.277 0.75)
			(stroke
				(width 0.15)
				(type solid)
			)
			(layer "B.SilkS")
		)
		(fp_line
			(start -0.927 0.351)
			(end -0.725 0.551)
			(stroke
				(width 0.15)
				(type solid)
			)
			(layer "B.SilkS")
		)
		(fp_line
			(start -0.927 0.051)
			(end -0.927 0.351)
			(stroke
				(width 0.15)
				(type solid)
			)
			(layer "B.SilkS")
		)
		(fp_circle
			(center -0.9652 -0.9652)
			(end -0.9152 -0.9652)
			(stroke
				(width 0.15)
				(type solid)
			)
			(fill yes)
			(layer "B.SilkS")
		)
		(fp_line
			(start -1.12 1.16)
			(end 1.1 1.16)
			(stroke
				(width 0.05)
				(type solid)
			)
			(layer "B.CrtYd")
		)
		(fp_line
			(start -1.12 1.16)
			(end -1.12 -1.15)
			(stroke
				(width 0.05)
				(type solid)
			)
			(layer "B.CrtYd")
		)
		(fp_line
			(start 1.1 1.16)
			(end 1.1 -1.15)
			(stroke
				(width 0.05)
				(type solid)
			)
			(layer "B.CrtYd")
		)
		(fp_line
			(start -1.12 -1.15)
			(end 1.1 -1.15)
			(stroke
				(width 0.05)
				(type solid)
			)
			(layer "B.CrtYd")
		)
		(fp_line
			(start -0.652 0.425)
			(end -0.802 0.276)
			(stroke
				(width 0.15)
				(type solid)
			)
			(layer "B.Fab")
		)
		(fp_line
			(start 0.8 0.425)
			(end -0.652 0.425)
			(stroke
				(width 0.15)
				(type solid)
			)
			(layer "B.Fab")
		)
		(fp_line
			(start 0.8 0.425)
			(end 0.8 -0.424)
			(stroke
				(width 0.15)
				(type solid)
			)
			(layer "B.Fab")
		)
		(fp_line
			(start -0.802 0.276)
			(end -0.802 -0.424)
			(stroke
				(width 0.15)
				(type solid)
			)
			(layer "B.Fab")
		)
		(fp_line
			(start 0.8 -0.424)
			(end -0.802 -0.424)
			(stroke
				(width 0.15)
				(type solid)
			)
			(layer "B.Fab")
		)
		(fp_circle
			(center -0.9652 -0.9652)
			(end -0.9144 -0.9652)
			(stroke
				(width 0.15)
				(type solid)
			)
			(fill no)
			(layer "B.Fab")
		)
		(fp_text user "License: Apache-2.0"
			(at -1.12 -5.024 90)
			(layer "B.Fab")
			(effects
				(font
					(size 0.7 0.7)
					(thickness 0.15)
				)
				(justify left bottom mirror)
			)
		)
		(fp_text user "${REFERENCE}"
			(at -1.12 -3.824 90)
			(layer "B.Fab")
			(effects
				(font
					(size 0.7 0.7)
					(thickness 0.15)
				)
				(justify left bottom mirror)
			)
		)
		(fp_text user "Author: Antmicro"
			(at -1.12 -6.224 90)
			(layer "B.Fab")
			(effects
				(font
					(size 0.7 0.7)
					(thickness 0.15)
				)
				(justify left bottom mirror)
			)
		)
		(pad "1" smd rect
			(at -0.5 -0.65 270)
			(size 0.4 0.51)
			(layers "B.Cu" "B.Mask" "B.Paste")
			(net 1285 "/SoM_Power/VIN_PWR_ON")
			(pinfunction "G")
			(pintype "input")
		)
		(pad "2" smd rect
			(at 0.498 -0.65 270)
			(size 0.4 0.51)
			(layers "B.Cu" "B.Mask" "B.Paste")
			(net 1 "GND")
			(pinfunction "S")
			(pintype "passive")
		)
		(pad "3" smd rect
			(at 0 0.652 270)
			(size 0.4 0.51)
			(layers "B.Cu" "B.Mask" "B.Paste")
			(net 1298 "Net-(Q37-G)")
			(pinfunction "D")
			(pintype "passive")
		)
	)
	(footprint "antmicro-footprints:R_0402_1005Metric"
		(layer "B.Cu")
		(at 92.87 148.17)
		(descr "Resistor SMD 0402")
		(tags "resistor SMD 0402")
		(property "Reference" "R202"
			(at 0.85 -0.369264 0)
			(layer "B.SilkS")
			(effects
				(font
					(size 0.7 0.7)
					(thickness 0.15)
				)
				(justify right top mirror)
			)
		)
		(property "Value" "R_0R_0402"
			(at -1.011843 -1.772046 0)
			(layer "B.Fab")
			(effects
				(font
					(size 0.7 0.7)
					(thickness 0.15)
				)
				(justify right top mirror)
			)
		)
		(property "Datasheet" "https://industrial.panasonic.com/cdbs/www-data/pdf/RDA0000/AOA0000C301.pdf"
			(at 0 0 0)
			(layer "B.Fab")
			(hide yes)
			(effects
				(font
					(size 1.27 1.27)
					(thickness 0.15)
				)
				(justify mirror)
			)
		)
		(property "Description" "SMD Chip Resistor, Jumper, 0 ohm, 100 mW, 0402 [1005 Metric], Thick Film, General Purpose"
			(at 0 0 0)
			(layer "B.Fab")
			(hide yes)
			(effects
				(font
					(size 1.27 1.27)
					(thickness 0.15)
				)
				(justify mirror)
			)
		)
		(property "MPN" "ERJ2GE0R00X"
			(at 0 0 180)
			(unlocked yes)
			(layer "B.Fab")
			(hide yes)
			(effects
				(font
					(size 1 1)
					(thickness 0.15)
				)
				(justify mirror)
			)
		)
		(property "Manufacturer" "Panasonic"
			(at 0 0 180)
			(unlocked yes)
			(layer "B.Fab")
			(hide yes)
			(effects
				(font
					(size 1 1)
					(thickness 0.15)
				)
				(justify mirror)
			)
		)
		(property "License" "Apache-2.0"
			(at 0 0 180)
			(unlocked yes)
			(layer "B.Fab")
			(hide yes)
			(effects
				(font
					(size 1 1)
					(thickness 0.15)
				)
				(justify mirror)
			)
		)
		(property "Author" "Antmicro"
			(at 0 0 180)
			(unlocked yes)
			(layer "B.Fab")
			(hide yes)
			(effects
				(font
					(size 1 1)
					(thickness 0.15)
				)
				(justify mirror)
			)
		)
		(property "Val" "0R"
			(at 0 0 180)
			(unlocked yes)
			(layer "B.Fab")
			(hide yes)
			(effects
				(font
					(size 1 1)
					(thickness 0.15)
				)
				(justify mirror)
			)
		)
		(property "Tolerance" "~"
			(at 0 0 180)
			(unlocked yes)
			(layer "B.Fab")
			(hide yes)
			(effects
				(font
					(size 1 1)
					(thickness 0.15)
				)
				(justify mirror)
			)
		)
		(property "Current" "1A"
			(at 0 0 180)
			(unlocked yes)
			(layer "B.Fab")
			(hide yes)
			(effects
				(font
					(size 1 1)
					(thickness 0.15)
				)
				(justify mirror)
			)
		)
		(sheetname "/SoM_IO2/")
		(sheetfile "som_io2.kicad_sch")
		(attr smd)
		(fp_poly
			(pts
				(xy -0.925 0.47) (xy -0.925 -0.47) (xy 0.925 -0.47) (xy 0.925 0.47)
			)
			(stroke
				(width 0.05)
				(type default)
			)
			(fill no)
			(layer "B.CrtYd")
		)
		(fp_poly
			(pts
				(xy -0.5 0.25) (xy -0.5 -0.25) (xy 0.5 -0.25) (xy 0.5 0.25)
			)
			(stroke
				(width 0.15)
				(type solid)
			)
			(fill no)
			(layer "B.Fab")
		)
		(fp_text user "Author: Antmicro"
			(at -0.95 -4.169 0)
			(layer "B.Fab")
			(effects
				(font
					(size 0.7 0.7)
					(thickness 0.15)
				)
				(justify right top mirror)
			)
		)
		(fp_text user "License: Apache-2.0"
			(at -0.949999 -5.169 0)
			(layer "B.Fab")
			(effects
				(font
					(size 0.7 0.7)
					(thickness 0.15)
				)
				(justify right top mirror)
			)
		)
		(fp_text user "${REFERENCE}"
			(at -0.95 -3.168 0)
			(layer "B.Fab")
			(effects
				(font
					(size 0.7 0.7)
					(thickness 0.15)
				)
				(justify right top mirror)
			)
		)
		(pad "1" smd roundrect
			(at -0.48 0)
			(size 0.59 0.64)
			(layers "B.Cu" "B.Mask" "B.Paste")
			(roundrect_rratio 0.25)
			(net 851 "/Expansion connector/PCIe_{C2x1}.CLK-")
			(pintype "passive")
		)
		(pad "2" smd roundrect
			(at 0.48 0)
			(size 0.59 0.64)
			(layers "B.Cu" "B.Mask" "B.Paste")
			(roundrect_rratio 0.25)
			(net 668 "/SoM_IO2/PCIe_{C2x1}R_CLK-")
			(pintype "passive")
		)
	)
	(footprint "antmicro-footprints:C_0402_1005Metric"
		(layer "B.Cu")
		(at 94 120.8 180)
		(descr "Capacitor SMD 0402")
		(tags "capacitor SMD 0402")
		(property "Reference" "C213"
			(at -3.9 -0.725 0)
			(layer "B.SilkS")
			(effects
				(font
					(size 0.7 0.7)
					(thickness 0.15)
				)
				(justify left bottom mirror)
			)
		)
		(property "Value" "C_220n_0402"
			(at -1.022927 -2.155213 0)
			(layer "B.Fab")
			(effects
				(font
					(size 0.7 0.7)
					(thickness 0.15)
				)
				(justify left bottom mirror)
			)
		)
		(property "Datasheet" "https://www.yageo.com/en/Chart/Download/pdf/CC0402KRX5R6BB224"
			(at 0 0 0)
			(layer "B.Fab")
			(hide yes)
			(effects
				(font
					(size 1.27 1.27)
					(thickness 0.15)
				)
				(justify mirror)
			)
		)
		(property "Description" "SMD Multilayer Ceramic Capacitor, 0.22 µF, 10 V, 0402 [1005 Metric], ± 10%, X5R, CC Series"
			(at 0 0 0)
			(layer "B.Fab")
			(hide yes)
			(effects
				(font
					(size 1.27 1.27)
					(thickness 0.15)
				)
				(justify mirror)
			)
		)
		(property "MPN" "CC0402KRX5R6BB224"
			(at 0 0 180)
			(unlocked yes)
			(layer "B.Fab")
			(hide yes)
			(effects
				(font
					(size 1 1)
					(thickness 0.15)
				)
				(justify mirror)
			)
		)
		(property "Val" "220n"
			(at 0 0 180)
			(unlocked yes)
			(layer "B.Fab")
			(hide yes)
			(effects
				(font
					(size 1 1)
					(thickness 0.15)
				)
				(justify mirror)
			)
		)
		(property "Voltage" "25V"
			(at 0 0 180)
			(unlocked yes)
			(layer "B.Fab")
			(hide yes)
			(effects
				(font
					(size 1 1)
					(thickness 0.15)
				)
				(justify mirror)
			)
		)
		(property "Dielectric" "X7R"
			(at 0 0 180)
			(unlocked yes)
			(layer "B.Fab")
			(hide yes)
			(effects
				(font
					(size 1 1)
					(thickness 0.15)
				)
				(justify mirror)
			)
		)
		(property "Manufacturer" "YAGEO"
			(at 0 0 180)
			(unlocked yes)
			(layer "B.Fab")
			(hide yes)
			(effects
				(font
					(size 1 1)
					(thickness 0.15)
				)
				(justify mirror)
			)
		)
		(property "License" "Apache-2.0"
			(at 0 0 180)
			(unlocked yes)
			(layer "B.Fab")
			(hide yes)
			(effects
				(font
					(size 1 1)
					(thickness 0.15)
				)
				(justify mirror)
			)
		)
		(property "Author" "Antmicro"
			(at 0 0 180)
			(unlocked yes)
			(layer "B.Fab")
			(hide yes)
			(effects
				(font
					(size 1 1)
					(thickness 0.15)
				)
				(justify mirror)
			)
		)
		(property "Public" "False"
			(at 0 0 180)
			(unlocked yes)
			(layer "B.Fab")
			(hide yes)
			(effects
				(font
					(size 1 1)
					(thickness 0.15)
				)
				(justify mirror)
			)
		)
		(sheetname "/Expansion connector/")
		(sheetfile "expansion_connector.kicad_sch")
		(attr smd)
		(fp_rect
			(start -0.925 0.47)
			(end 0.925 -0.47)
			(stroke
				(width 0.05)
				(type default)
			)
			(fill no)
			(layer "B.CrtYd")
		)
		(fp_line
			(start 0.504 0.25)
			(end 0.504 -0.248)
			(stroke
				(width 0.15)
				(type solid)
			)
			(layer "B.Fab")
		)
		(fp_line
			(start 0.504 -0.248)
			(end -0.494 -0.248)
			(stroke
				(width 0.15)
				(type solid)
			)
			(layer "B.Fab")
		)
		(fp_line
			(start -0.494 0.25)
			(end 0.504 0.25)
			(stroke
				(width 0.15)
				(type solid)
			)
			(layer "B.Fab")
		)
		(fp_line
			(start -0.494 -0.248)
			(end -0.494 0.25)
			(stroke
				(width 0.15)
				(type solid)
			)
			(layer "B.Fab")
		)
		(fp_text user "Author: Antmicro"
			(at -0.939 -3.399 0)
			(layer "B.Fab")
			(effects
				(font
					(size 0.7 0.7)
					(thickness 0.15)
				)
				(justify left bottom mirror)
			)
		)
		(fp_text user "${REFERENCE}"
			(at -0.939 -4.599 0)
			(layer "B.Fab")
			(effects
				(font
					(size 0.7 0.7)
					(thickness 0.15)
				)
				(justify left bottom mirror)
			)
		)
		(fp_text user "License: Apache-2.0"
			(at -0.939 -5.799 0)
			(layer "B.Fab")
			(effects
				(font
					(size 0.7 0.7)
					(thickness 0.15)
				)
				(justify left bottom mirror)
			)
		)
		(pad "1" smd roundrect
			(at -0.48 0 180)
			(size 0.59 0.64)
			(layers "B.Cu" "B.Mask" "B.Paste")
			(roundrect_rratio 0.25)
			(net 478 "/Expansion connector/PCIe_{C2x1}.TX0+")
			(pintype "passive")
		)
		(pad "2" smd roundrect
			(at 0.48 0 180)
			(size 0.59 0.64)
			(layers "B.Cu" "B.Mask" "B.Paste")
			(roundrect_rratio 0.25)
			(net 476 "/Expansion connector/PET0_C2_P")
			(pintype "passive")
		)
	)
	(footprint "antmicro-footprints:R_0402_1005Metric"
		(layer "B.Cu")
		(at 202.626 144.012)
		(descr "Resistor SMD 0402")
		(tags "resistor SMD 0402")
		(property "Reference" "R187"
			(at -1.4 -1.412 0)
			(layer "B.SilkS")
			(effects
				(font
					(size 0.7 0.7)
					(thickness 0.15)
				)
				(justify right top mirror)
			)
		)
		(property "Value" "R_0R_0402"
			(at -1.011843 -1.772047 0)
			(layer "B.Fab")
			(effects
				(font
					(size 0.7 0.7)
					(thickness 0.15)
				)
				(justify right top mirror)
			)
		)
		(property "Datasheet" "https://industrial.panasonic.com/cdbs/www-data/pdf/RDA0000/AOA0000C301.pdf"
			(at 0 0 0)
			(layer "B.Fab")
			(hide yes)
			(effects
				(font
					(size 1.27 1.27)
					(thickness 0.15)
				)
				(justify mirror)
			)
		)
		(property "Description" "SMD Chip Resistor, Jumper, 0 ohm, 100 mW, 0402 [1005 Metric], Thick Film, General Purpose"
			(at 0 0 0)
			(layer "B.Fab")
			(hide yes)
			(effects
				(font
					(size 1.27 1.27)
					(thickness 0.15)
				)
				(justify mirror)
			)
		)
		(property "MPN" "ERJ2GE0R00X"
			(at 0 0 180)
			(unlocked yes)
			(layer "B.Fab")
			(hide yes)
			(effects
				(font
					(size 1 1)
					(thickness 0.15)
				)
				(justify mirror)
			)
		)
		(property "Manufacturer" "Panasonic"
			(at 0 0 180)
			(unlocked yes)
			(layer "B.Fab")
			(hide yes)
			(effects
				(font
					(size 1 1)
					(thickness 0.15)
				)
				(justify mirror)
			)
		)
		(property "License" "Apache-2.0"
			(at 0 0 180)
			(unlocked yes)
			(layer "B.Fab")
			(hide yes)
			(effects
				(font
					(size 1 1)
					(thickness 0.15)
				)
				(justify mirror)
			)
		)
		(property "Author" "Antmicro"
			(at 0 0 180)
			(unlocked yes)
			(layer "B.Fab")
			(hide yes)
			(effects
				(font
					(size 1 1)
					(thickness 0.15)
				)
				(justify mirror)
			)
		)
		(property "Val" "0R"
			(at 0 0 180)
			(unlocked yes)
			(layer "B.Fab")
			(hide yes)
			(effects
				(font
					(size 1 1)
					(thickness 0.15)
				)
				(justify mirror)
			)
		)
		(property "Tolerance" "~"
			(at 0 0 180)
			(unlocked yes)
			(layer "B.Fab")
			(hide yes)
			(effects
				(font
					(size 1 1)
					(thickness 0.15)
				)
				(justify mirror)
			)
		)
		(property "Current" "1A"
			(at 0 0 180)
			(unlocked yes)
			(layer "B.Fab")
			(hide yes)
			(effects
				(font
					(size 1 1)
					(thickness 0.15)
				)
				(justify mirror)
			)
		)
		(sheetname "/SFP/")
		(sheetfile "sfp.kicad_sch")
		(attr smd)
		(fp_rect
			(start -0.925 0.47)
			(end 0.925 -0.47)
			(stroke
				(width 0.05)
				(type default)
			)
			(fill no)
			(layer "B.CrtYd")
		)
		(fp_rect
			(start -0.5 0.25)
			(end 0.5 -0.25)
			(stroke
				(width 0.15)
				(type solid)
			)
			(fill no)
			(layer "B.Fab")
		)
		(fp_text user "Author: Antmicro"
			(at -0.95 -4.169 0)
			(layer "B.Fab")
			(effects
				(font
					(size 0.7 0.7)
					(thickness 0.15)
				)
				(justify right top mirror)
			)
		)
		(fp_text user "License: Apache-2.0"
			(at -0.95 -5.169 0)
			(layer "B.Fab")
			(effects
				(font
					(size 0.7 0.7)
					(thickness 0.15)
				)
				(justify right top mirror)
			)
		)
		(fp_text user "${REFERENCE}"
			(at -0.95 -3.168 0)
			(layer "B.Fab")
			(effects
				(font
					(size 0.7 0.7)
					(thickness 0.15)
				)
				(justify right top mirror)
			)
		)
		(pad "1" smd roundrect
			(at -0.48 0)
			(size 0.59 0.64)
			(layers "B.Cu" "B.Mask" "B.Paste")
			(roundrect_rratio 0.25)
			(net 57 "/SFP/MOD_ABS")
			(pintype "passive")
		)
		(pad "2" smd roundrect
			(at 0.48 0)
			(size 0.59 0.64)
			(layers "B.Cu" "B.Mask" "B.Paste")
			(roundrect_rratio 0.25)
			(net 1296 "/SFP/SFP_MOD_ABS")
			(pintype "passive")
		)
	)
)
